(kicad_pcb
	(version 20260206)
	(generator "pcbnew")
	(generator_version "10.0")
	(general
		(thickness 1.6)
		(legacy_teardrops no)
	)
	(paper "A4")
	(title_block
		(title "pdpb — Lightning_PDPB_BRD.brd")
		(comment 1 "Lightning (Wiwynn / Facebook NVMe JBOF) / footprints 874-875 of 1140")
	)
	(layers
		(0 "F.Cu" signal "TOP")
		(4 "In1.Cu" signal "L2GND")
		(6 "In2.Cu" signal "L3")
		(8 "In3.Cu" signal "L4VCC")
		(10 "In4.Cu" signal "L5VCC")
		(12 "In5.Cu" signal "L6")
		(14 "In6.Cu" signal "L7GND")
		(2 "B.Cu" signal "BOTTOM")
		(9 "F.Adhes" user "F.Adhesive")
		(11 "B.Adhes" user "B.Adhesive")
		(13 "F.Paste" user "Package Geometry/Pastemask Top")
		(15 "B.Paste" user "Package Geometry/Pastemask Bottom")
		(5 "F.SilkS" user "Ref Des/Silkscreen Top")
		(7 "B.SilkS" user "Ref Des/Silkscreen Bottom")
		(1 "F.Mask" user "Board Geometry/Soldermask Top")
		(3 "B.Mask" user "Board Geometry/Soldermask Bottom")
		(17 "Dwgs.User" user "User.Drawings")
		(19 "Cmts.User" user "User.Comments")
		(21 "Eco1.User" user "User.Eco1")
		(23 "Eco2.User" user "User.Eco2")
		(25 "Edge.Cuts" user "Board Geometry/Outline")
		(27 "Margin" user)
		(31 "F.CrtYd" user "Package Geometry/Place Bound Top")
		(29 "B.CrtYd" user "Package Geometry/Place Bound Bottom")
		(35 "F.Fab" user "Ref Des/Assembly Top")
		(33 "B.Fab" user "Ref Des/Assembly Bottom")
	)
	(footprint ""
		(layer "F.Cu")
		(at 93.98 -101.6 90)
		(property "Reference" "EU4"
			(at 0 0 90)
			(layer "F.SilkS")
			(hide yes)
			(effects
				(font
					(size 1.27 1.27)
				)
			)
		)
		(property "Value" "9ZXL1231AKLFT-GP"
			(at -6.5278 -7.2009 90)
			(unlocked yes)
			(layer "F.Fab")
			(hide yes)
			(effects
				(font
					(size 1.016 1.016)
					(thickness 0.1524)
				)
			)
		)
		(property "Device Type" "QFN64G9-G6D25H40"
			(at -6.5278 -8.7249 90)
			(unlocked yes)
			(layer "F.Fab")
			(hide yes)
			(effects
				(font
					(size 1.016 1.016)
					(thickness 0.1524)
				)
			)
		)
		(duplicate_pad_numbers_are_jumpers no)
		(fp_line
			(start 1.7526 -5.71881)
			(end 1.7526 -5.21081)
			(stroke
				(width 0.1524)
				(type default)
			)
			(layer "F.SilkS")
		)
		(fp_line
			(start -3.2639 -5.71881)
			(end -3.2639 -5.21081)
			(stroke
				(width 0.1524)
				(type default)
			)
			(layer "F.SilkS")
		)
		(fp_line
			(start -3.9878 -5.5118)
			(end -5.5118 -5.5118)
			(stroke
				(width 0.1524)
				(type default)
			)
			(layer "F.SilkS")
		)
		(fp_line
			(start -5.5118 -5.5118)
			(end -5.5118 -3.9243)
			(stroke
				(width 0.1524)
				(type default)
			)
			(layer "F.SilkS")
		)
		(fp_line
			(start -0.74041 -5.21081)
			(end -0.74041 -5.97281)
			(stroke
				(width 0.1524)
				(type default)
			)
			(layer "F.SilkS")
		)
		(fp_line
			(start -5.97281 -2.2606)
			(end -5.21081 -2.2606)
			(stroke
				(width 0.1524)
				(type default)
			)
			(layer "F.SilkS")
		)
		(fp_line
			(start 5.21081 -1.778)
			(end 5.97281 -1.778)
			(stroke
				(width 0.1524)
				(type default)
			)
			(layer "F.SilkS")
		)
		(fp_line
			(start -5.21081 0.254)
			(end -5.71881 0.254)
			(stroke
				(width 0.1524)
				(type default)
			)
			(layer "F.SilkS")
		)
		(fp_line
			(start 5.71881 0.7112)
			(end 5.21081 0.7112)
			(stroke
				(width 0.1524)
				(type default)
			)
			(layer "F.SilkS")
		)
		(fp_line
			(start -5.97281 2.7432)
			(end -5.21081 2.7432)
			(stroke
				(width 0.1524)
				(type default)
			)
			(layer "F.SilkS")
		)
		(fp_line
			(start 5.21081 3.22961)
			(end 5.97281 3.22961)
			(stroke
				(width 0.1524)
				(type default)
			)
			(layer "F.SilkS")
		)
		(fp_line
			(start -5.4991 4.1148)
			(end -5.4991 5.5118)
			(stroke
				(width 0.1524)
				(type default)
			)
			(layer "F.SilkS")
		)
		(fp_line
			(start 2.2352 5.21081)
			(end 2.2352 5.71881)
			(stroke
				(width 0.1524)
				(type default)
			)
			(layer "F.SilkS")
		)
		(fp_line
			(start -2.7432 5.21081)
			(end -2.7432 5.71881)
			(stroke
				(width 0.1524)
				(type default)
			)
			(layer "F.SilkS")
		)
		(fp_line
			(start 5.5118 5.4991)
			(end 5.5118 3.9878)
			(stroke
				(width 0.1524)
				(type default)
			)
			(layer "F.SilkS")
		)
		(fp_line
			(start 4.0767 5.4991)
			(end 5.5118 5.4991)
			(stroke
				(width 0.1524)
				(type default)
			)
			(layer "F.SilkS")
		)
		(fp_line
			(start -5.4991 5.5118)
			(end -4.2037 5.5118)
			(stroke
				(width 0.1524)
				(type default)
			)
			(layer "F.SilkS")
		)
		(fp_line
			(start -0.7366 5.97281)
			(end -0.7366 5.21081)
			(stroke
				(width 0.1524)
				(type default)
			)
			(layer "F.SilkS")
		)
		(fp_poly
			(pts
				(xy 5.5118 -4.05511) (xy 4.05511 -5.5118) (xy 5.5118 -5.5118)
			)
			(stroke
				(width 0)
				(type default)
			)
			(fill yes)
			(layer "F.SilkS")
		)
		(fp_rect
			(start -4.4958 4.4958)
			(end 4.4958 -4.4958)
			(stroke
				(width 0)
				(type default)
			)
			(fill no)
			(layer "F.CrtYd")
		)
		(fp_poly
			(pts
				(xy -5.5118 5.5118) (xy -5.5118 -5.5118) (xy 5.5118 -5.5118) (xy 5.5118 -0.5461) (xy 4.4958 -0.5461)
				(xy 4.4958 -4.4958) (xy -4.4958 -4.4958) (xy -4.4958 4.4958) (xy 4.4958 4.4958) (xy 4.4958 -0.5334)
				(xy 5.5118 -0.5334) (xy 5.5118 5.5118)
			)
			(stroke
				(width 0)
				(type default)
			)
			(fill no)
			(layer "F.CrtYd")
		)
		(fp_rect
			(start -5.5118 5.5118)
			(end 5.5118 -5.5118)
			(stroke
				(width 0)
				(type default)
			)
			(fill no)
			(layer "F.Fab")
		)
		(pad "1" smd rect
			(at 3.75031 -4.550918 90)
			(size 0.3048 0.9144)
			(layers "F.Cu" "F.Mask" "F.Paste")
			(net "VDDA_4")
		)
		(pad "2" smd rect
			(at 3.24993 -4.42341 90)
			(size 0.3048 1.1684)
			(layers "F.Cu" "F.Mask" "F.Paste")
			(net "GND")
		)
		(pad "3" smd rect
			(at 2.74955 -4.42341 90)
			(size 0.3048 1.1684)
			(layers "F.Cu" "F.Mask" "F.Paste")
			(net "Net_1319")
		)
		(pad "4" smd rect
			(at 2.25044 -4.42341 90)
			(size 0.3048 1.1684)
			(layers "F.Cu" "F.Mask" "F.Paste")
			(net "CLK_BUF_EU4_100M_133M#")
		)
		(pad "5" smd rect
			(at 1.75006 -4.42341 90)
			(size 0.3048 1.1684)
			(layers "F.Cu" "F.Mask" "F.Paste")
			(net "CLK_BUF_EU4_HIBW_BYPM_LOBW#")
		)
		(pad "6" smd rect
			(at 1.24968 -4.42341 90)
			(size 0.3048 1.1684)
			(layers "F.Cu" "F.Mask" "F.Paste")
			(net "P3V3_PG")
		)
		(pad "7" smd rect
			(at 0.75057 -4.42341 90)
			(size 0.3048 1.1684)
			(layers "F.Cu" "F.Mask" "F.Paste")
			(net "GND")
		)
		(pad "8" smd rect
			(at 0.25019 -4.42341 90)
			(size 0.3048 1.1684)
			(layers "F.Cu" "F.Mask" "F.Paste")
			(net "VDDR_4")
		)
		(pad "9" smd rect
			(at -0.25019 -4.42341 90)
			(size 0.3048 1.1684)
			(layers "F.Cu" "F.Mask" "F.Paste")
			(net "PE_100M_CLK1_P")
		)
		(pad "10" smd rect
			(at -0.75057 -4.42341 90)
			(size 0.3048 1.1684)
			(layers "F.Cu" "F.Mask" "F.Paste")
			(net "PE_100M_CLK1_N")
		)
		(pad "11" smd rect
			(at -1.24968 -4.42341 90)
			(size 0.3048 1.1684)
			(layers "F.Cu" "F.Mask" "F.Paste")
			(net "CLK_BUF_EU4_SMB_A0_TRI")
		)
		(pad "12" smd rect
			(at -1.75006 -4.42341 90)
			(size 0.3048 1.1684)
			(layers "F.Cu" "F.Mask" "F.Paste")
			(net "I2C_SDA_BUF_8_EU4_R")
		)
		(pad "13" smd rect
			(at -2.25044 -4.42341 90)
			(size 0.3048 1.1684)
			(layers "F.Cu" "F.Mask" "F.Paste")
			(net "I2C_SCL_BUF_8_EU4_R")
		)
		(pad "14" smd rect
			(at -2.74955 -4.42341 90)
			(size 0.3048 1.1684)
			(layers "F.Cu" "F.Mask" "F.Paste")
			(net "CLK_BUF_EU4_SMB_A1_TRI")
		)
		(pad "15" smd rect
			(at -3.24993 -4.42341 90)
			(size 0.3048 1.1684)
			(layers "F.Cu" "F.Mask" "F.Paste")
			(net "Net_1325")
		)
		(pad "16" smd rect
			(at -3.75031 -4.550918 90)
			(size 0.3048 0.9144)
			(layers "F.Cu" "F.Mask" "F.Paste")
			(net "Net_1324")
		)
		(pad "17" smd rect
			(at -4.550918 -3.75031 90)
			(size 0.9144 0.3048)
			(layers "F.Cu" "F.Mask" "F.Paste")
			(net "PE_CLK_100M_DR9_2_R_P")
		)
		(pad "18" smd rect
			(at -4.42341 -3.24993 90)
			(size 1.1684 0.3048)
			(layers "F.Cu" "F.Mask" "F.Paste")
			(net "PE_CLK_100M_DR9_2_R_N")
		)
		(pad "19" smd rect
			(at -4.42341 -2.74955 90)
			(size 1.1684 0.3048)
			(layers "F.Cu" "F.Mask" "F.Paste")
			(net "SSD_PRSNT9")
		)
		(pad "20" smd rect
			(at -4.42341 -2.25044 90)
			(size 1.1684 0.3048)
			(layers "F.Cu" "F.Mask" "F.Paste")
			(net "SSD9_CLK0_OE_R_N")
		)
		(pad "21" smd rect
			(at -4.42341 -1.75006 90)
			(size 1.1684 0.3048)
			(layers "F.Cu" "F.Mask" "F.Paste")
			(net "PE_CLK_100M_DR9_1_R_P")
		)
		(pad "22" smd rect
			(at -4.42341 -1.24968 90)
			(size 1.1684 0.3048)
			(layers "F.Cu" "F.Mask" "F.Paste")
			(net "PE_CLK_100M_DR9_1_R_N")
		)
		(pad "23" smd rect
			(at -4.42341 -0.75057 90)
			(size 1.1684 0.3048)
			(layers "F.Cu" "F.Mask" "F.Paste")
			(net "GND")
		)
		(pad "24" smd rect
			(at -4.42341 -0.25019 90)
			(size 1.1684 0.3048)
			(layers "F.Cu" "F.Mask" "F.Paste")
			(net "VDD_DIFF_4")
		)
		(pad "25" smd rect
			(at -4.42341 0.25019 90)
			(size 1.1684 0.3048)
			(layers "F.Cu" "F.Mask" "F.Paste")
			(net "VDD_IO_4")
		)
		(pad "26" smd rect
			(at -4.42341 0.75057 90)
			(size 1.1684 0.3048)
			(layers "F.Cu" "F.Mask" "F.Paste")
			(net "PE_CLK_100M_DR14_2_R_P")
		)
		(pad "27" smd rect
			(at -4.42341 1.24968 90)
			(size 1.1684 0.3048)
			(layers "F.Cu" "F.Mask" "F.Paste")
			(net "PE_CLK_100M_DR14_2_R_N")
		)
		(pad "28" smd rect
			(at -4.42341 1.75006 90)
			(size 1.1684 0.3048)
			(layers "F.Cu" "F.Mask" "F.Paste")
			(net "SSD_PRSNT14")
		)
		(pad "29" smd rect
			(at -4.42341 2.25044 90)
			(size 1.1684 0.3048)
			(layers "F.Cu" "F.Mask" "F.Paste")
			(net "SSD14_CLK0_OE_R_N")
		)
		(pad "30" smd rect
			(at -4.42341 2.74955 90)
			(size 1.1684 0.3048)
			(layers "F.Cu" "F.Mask" "F.Paste")
			(net "PE_CLK_100M_DR14_1_R_P")
		)
		(pad "31" smd rect
			(at -4.42341 3.24993 90)
			(size 1.1684 0.3048)
			(layers "F.Cu" "F.Mask" "F.Paste")
			(net "PE_CLK_100M_DR14_1_R_N")
		)
		(pad "32" smd rect
			(at -4.550918 3.75031 90)
			(size 0.9144 0.3048)
			(layers "F.Cu" "F.Mask" "F.Paste")
			(net "VDD_IO_4")
		)
		(pad "33" smd rect
			(at -3.75031 4.550918 90)
			(size 0.3048 0.9144)
			(layers "F.Cu" "F.Mask" "F.Paste")
			(net "GND")
		)
		(pad "34" smd rect
			(at -3.24993 4.42341 90)
			(size 0.3048 1.1684)
			(layers "F.Cu" "F.Mask" "F.Paste")
			(net "Net_317")
		)
		(pad "35" smd rect
			(at -2.74955 4.42341 90)
			(size 0.3048 1.1684)
			(layers "F.Cu" "F.Mask" "F.Paste")
			(net "Net_316")
		)
		(pad "36" smd rect
			(at -2.25044 4.42341 90)
			(size 0.3048 1.1684)
			(layers "F.Cu" "F.Mask" "F.Paste")
			(net "CLK_BUFFER_EU4_VOE_N")
		)
		(pad "37" smd rect
			(at -1.75006 4.42341 90)
			(size 0.3048 1.1684)
			(layers "F.Cu" "F.Mask" "F.Paste")
			(net "CLK_BUFFER_EU4_VOE_N")
		)
		(pad "38" smd rect
			(at -1.24968 4.42341 90)
			(size 0.3048 1.1684)
			(layers "F.Cu" "F.Mask" "F.Paste")
			(net "Net_319")
		)
		(pad "39" smd rect
			(at -0.75057 4.42341 90)
			(size 0.3048 1.1684)
			(layers "F.Cu" "F.Mask" "F.Paste")
			(net "Net_318")
		)
		(pad "40" smd rect
			(at -0.25019 4.42341 90)
			(size 0.3048 1.1684)
			(layers "F.Cu" "F.Mask" "F.Paste")
			(net "VDD_DIFF_4")
		)
		(pad "41" smd rect
			(at 0.25019 4.42341 90)
			(size 0.3048 1.1684)
			(layers "F.Cu" "F.Mask" "F.Paste")
			(net "GND")
		)
		(pad "42" smd rect
			(at 0.75057 4.42341 90)
			(size 0.3048 1.1684)
			(layers "F.Cu" "F.Mask" "F.Paste")
			(net "Net_1320")
		)
		(pad "43" smd rect
			(at 1.24968 4.42341 90)
			(size 0.3048 1.1684)
			(layers "F.Cu" "F.Mask" "F.Paste")
			(net "Net_1321")
		)
		(pad "44" smd rect
			(at 1.75006 4.42341 90)
			(size 0.3048 1.1684)
			(layers "F.Cu" "F.Mask" "F.Paste")
			(net "CLK_BUFFER_EU4_VOE_N")
		)
		(pad "45" smd rect
			(at 2.25044 4.42341 90)
			(size 0.3048 1.1684)
			(layers "F.Cu" "F.Mask" "F.Paste")
			(net "CLK_BUFFER_EU4_VOE_N")
		)
		(pad "46" smd rect
			(at 2.74955 4.42341 90)
			(size 0.3048 1.1684)
			(layers "F.Cu" "F.Mask" "F.Paste")
			(net "Net_1322")
		)
		(pad "47" smd rect
			(at 3.24993 4.42341 90)
			(size 0.3048 1.1684)
			(layers "F.Cu" "F.Mask" "F.Paste")
			(net "Net_1323")
		)
		(pad "48" smd rect
			(at 3.75031 4.550918 90)
			(size 0.3048 0.9144)
			(layers "F.Cu" "F.Mask" "F.Paste")
			(net "GND")
		)
		(pad "49" smd rect
			(at 4.550918 3.75031 90)
			(size 0.9144 0.3048)
			(layers "F.Cu" "F.Mask" "F.Paste")
			(net "VDD_IO_4")
		)
		(pad "50" smd rect
			(at 4.42341 3.24993 90)
			(size 1.1684 0.3048)
			(layers "F.Cu" "F.Mask" "F.Paste")
			(net "PE_CLK_100M_DR8_2_R_P")
		)
		(pad "51" smd rect
			(at 4.42341 2.74955 90)
			(size 1.1684 0.3048)
			(layers "F.Cu" "F.Mask" "F.Paste")
			(net "PE_CLK_100M_DR8_2_R_N")
		)
		(pad "52" smd rect
			(at 4.42341 2.25044 90)
			(size 1.1684 0.3048)
			(layers "F.Cu" "F.Mask" "F.Paste")
			(net "SSD_PRSNT8")
		)
		(pad "53" smd rect
			(at 4.42341 1.75006 90)
			(size 1.1684 0.3048)
			(layers "F.Cu" "F.Mask" "F.Paste")
			(net "SSD8_CLK0_OE_R_N")
		)
		(pad "54" smd rect
			(at 4.42341 1.24968 90)
			(size 1.1684 0.3048)
			(layers "F.Cu" "F.Mask" "F.Paste")
			(net "PE_CLK_100M_DR8_1_R_P")
		)
		(pad "55" smd rect
			(at 4.42341 0.75057 90)
			(size 1.1684 0.3048)
			(layers "F.Cu" "F.Mask" "F.Paste")
			(net "PE_CLK_100M_DR8_1_R_N")
		)
		(pad "56" smd rect
			(at 4.42341 0.25019 90)
			(size 1.1684 0.3048)
			(layers "F.Cu" "F.Mask" "F.Paste")
			(net "VDD_IO_4")
		)
		(pad "57" smd rect
			(at 4.42341 -0.25019 90)
			(size 1.1684 0.3048)
			(layers "F.Cu" "F.Mask" "F.Paste")
			(net "VDD_DIFF_4")
		)
		(pad "58" smd rect
			(at 4.42341 -0.75057 90)
			(size 1.1684 0.3048)
			(layers "F.Cu" "F.Mask" "F.Paste")
			(net "GND")
		)
		(pad "59" smd rect
			(at 4.42341 -1.24968 90)
			(size 1.1684 0.3048)
			(layers "F.Cu" "F.Mask" "F.Paste")
			(net "PE_CLK_100M_DR13_2_R_P")
		)
		(pad "60" smd rect
			(at 4.42341 -1.75006 90)
			(size 1.1684 0.3048)
			(layers "F.Cu" "F.Mask" "F.Paste")
			(net "PE_CLK_100M_DR13_2_R_N")
		)
		(pad "61" smd rect
			(at 4.42341 -2.25044 90)
			(size 1.1684 0.3048)
			(layers "F.Cu" "F.Mask" "F.Paste")
			(net "SSD_PRSNT13")
		)
		(pad "62" smd rect
			(at 4.42341 -2.74955 90)
			(size 1.1684 0.3048)
			(layers "F.Cu" "F.Mask" "F.Paste")
			(net "SSD13_CLK0_OE_R_N")
		)
		(pad "63" smd rect
			(at 4.42341 -3.24993 90)
			(size 1.1684 0.3048)
			(layers "F.Cu" "F.Mask" "F.Paste")
			(net "PE_CLK_100M_DR13_1_R_P")
		)
		(pad "64" smd rect
			(at 4.550918 -3.75031 90)
			(size 0.9144 0.3048)
			(layers "F.Cu" "F.Mask" "F.Paste")
			(net "PE_CLK_100M_DR13_1_R_N")
		)
		(pad "65" smd rect
			(at 0 0 90)
			(size 6.2484 6.2484)
			(layers "F.Cu" "F.Mask" "F.Paste")
			(net "GND")
		)
	)
	(footprint ""
		(layer "F.Cu")
		(at 98.298 -425.831 90)
		(property "Reference" "C8838"
			(at 0 0 90)
			(layer "F.SilkS")
			(hide yes)
			(effects
				(font
					(size 1.27 1.27)
				)
			)
		)
		(property "Value" "SCD1U16V2KX-3GP"
			(at 1.1811 -2.7051 90)
			(unlocked yes)
			(layer "F.Fab")
			(hide yes)
			(effects
				(font
					(size 1.016 1.016)
					(thickness 0.1524)
				)
			)
		)
		(property "Device Type" "C402H22"
			(at 1.1811 -4.2291 90)
			(unlocked yes)
			(layer "F.Fab")
			(hide yes)
			(effects
				(font
					(size 1.016 1.016)
					(thickness 0.1524)
				)
			)
		)
		(duplicate_pad_numbers_are_jumpers no)
		(fp_rect
			(start -0.4318 0.9525)
			(end 0.4318 -0.9525)
			(stroke
				(width 0)
				(type default)
			)
			(fill no)
			(layer "F.CrtYd")
		)
		(fp_rect
			(start -0.4318 0.9525)
			(end 0.4318 -0.9525)
			(stroke
				(width 0)
				(type default)
			)
			(fill no)
			(layer "F.Fab")
		)
		(pad "1" smd custom
			(at 0 -0.4445 90)
			(size 0.1524 0.1524)
			(layers "F.Cu" "F.Mask" "F.Paste")
			(net "VDD_IO_1")
			(options
				(clearance outline)
				(anchor circle)
			)
			(primitives
				(gr_poly
					(pts
						(arc
							(start 0.3048 -0.2032)
							(mid 0.275042 -0.275042)
							(end 0.2032 -0.3048)
						)
						(arc
							(start -0.2032 -0.3048)
							(mid -0.275042 -0.275042)
							(end -0.3048 -0.2032)
						)
						(arc
							(start -0.3048 0.2032)
							(mid -0.275042 0.275042)
							(end -0.2032 0.3048)
						)
						(arc
							(start 0.2032 0.3048)
							(mid 0.275042 0.275042)
							(end 0.3048 0.2032)
						)
					)
					(width 0)
					(fill yes)
				)
			)
		)
		(pad "2" smd custom
			(at 0 0.4445 90)
			(size 0.1524 0.1524)
			(layers "F.Cu" "F.Mask" "F.Paste")
			(net "GND")
			(options
				(clearance outline)
				(anchor circle)
			)
			(primitives
				(gr_poly
					(pts
						(arc
							(start 0.3048 -0.2032)
							(mid 0.275042 -0.275042)
							(end 0.2032 -0.3048)
						)
						(arc
							(start -0.2032 -0.3048)
							(mid -0.275042 -0.275042)
							(end -0.3048 -0.2032)
						)
						(arc
							(start -0.3048 0.2032)
							(mid -0.275042 0.275042)
							(end -0.2032 0.3048)
						)
						(arc
							(start 0.2032 0.3048)
							(mid 0.275042 0.275042)
							(end 0.3048 0.2032)
						)
					)
					(width 0)
					(fill yes)
				)
			)
		)
	)
)
